(kicad_pcb
	(version 20260206)
	(generator "pcbnew")
	(generator_version "10.0")
	(general
		(thickness 1.6)
		(legacy_teardrops no)
	)
	(paper "A4")
	(title_block
		(title "01162023_DA0F0TEBIF0_F0T_Expander_BD_F_brd_V02_OCP.brd")
		(comment 1 "Grand Teton / footprints 9533-9538 of 9728")
	)
	(layers
		(0 "F.Cu" signal "TOP")
		(4 "In1.Cu" signal "GND")
		(6 "In2.Cu" signal "VCC")
		(8 "In3.Cu" signal "VCC1")
		(10 "In4.Cu" signal "GND1")
		(12 "In5.Cu" signal "IN1")
		(14 "In6.Cu" signal "GND2")
		(16 "In7.Cu" signal "IN2")
		(18 "In8.Cu" signal "GND3")
		(20 "In9.Cu" signal "IN3")
		(22 "In10.Cu" signal "GND4")
		(24 "In11.Cu" signal "IN4")
		(26 "In12.Cu" signal "GND5")
		(28 "In13.Cu" signal "IN5")
		(30 "In14.Cu" signal "GND6")
		(32 "In15.Cu" signal "IN6")
		(34 "In16.Cu" signal "GND7")
		(2 "B.Cu" signal "BOTTOM")
		(9 "F.Adhes" user "F.Adhesive")
		(11 "B.Adhes" user "B.Adhesive")
		(13 "F.Paste" user "Package Geometry/Pastemask Top")
		(15 "B.Paste" user "Package Geometry/Pastemask Bottom")
		(5 "F.SilkS" user "Ref Des/Silkscreen Top")
		(7 "B.SilkS" user "Ref Des/Silkscreen Bottom")
		(1 "F.Mask" user "Board Geometry/Soldermask Top")
		(3 "B.Mask" user "Board Geometry/Soldermask Bottom")
		(17 "Dwgs.User" user "User.Drawings")
		(19 "Cmts.User" user "User.Comments")
		(21 "Eco1.User" user "User.Eco1")
		(23 "Eco2.User" user "User.Eco2")
		(25 "Edge.Cuts" user "Board Geometry/Outline")
		(27 "Margin" user)
		(31 "F.CrtYd" user "Package Geometry/Place Bound Top")
		(29 "B.CrtYd" user "Package Geometry/Place Bound Bottom")
		(35 "F.Fab" user "Ref Des/Assembly Top")
		(33 "B.Fab" user "Ref Des/Assembly Bottom")
	)
	(footprint ""
		(layer "B.Cu")
		(at 140.894816 -203.552806 180)
		(property "Reference" "C2600"
			(at 0 0 0)
			(layer "B.SilkS")
			(hide yes)
			(effects
				(font
					(size 1.27 1.27)
				)
				(justify mirror)
			)
		)
		(property "Value" ""
			(at 0 0 0)
			(layer "B.Fab")
			(effects
				(font
					(size 1.27 1.27)
				)
				(justify mirror)
			)
		)
		(duplicate_pad_numbers_are_jumpers no)
		(fp_line
			(start 1.2954 0.5842)
			(end 1.2954 -0.5842)
			(stroke
				(width 0.1524)
				(type default)
			)
			(layer "B.SilkS")
		)
		(fp_line
			(start 1.2954 -0.5842)
			(end -1.2954 -0.5842)
			(stroke
				(width 0.1524)
				(type default)
			)
			(layer "B.SilkS")
		)
		(fp_line
			(start -1.2954 0.5842)
			(end 1.2954 0.5842)
			(stroke
				(width 0.1524)
				(type default)
			)
			(layer "B.SilkS")
		)
		(fp_line
			(start -1.2954 -0.5842)
			(end -1.2954 0.5842)
			(stroke
				(width 0.1524)
				(type default)
			)
			(layer "B.SilkS")
		)
		(fp_line
			(start 1.1938 0.4064)
			(end 1.1938 -0.4064)
			(stroke
				(width 0.1)
				(type default)
			)
			(layer "B.Fab")
		)
		(fp_line
			(start 1.1938 -0.4064)
			(end 0.8636 -0.4064)
			(stroke
				(width 0.1)
				(type default)
			)
			(layer "B.Fab")
		)
		(fp_line
			(start 0.8636 0.4572)
			(end 0.8636 0.4064)
			(stroke
				(width 0.1)
				(type default)
			)
			(layer "B.Fab")
		)
		(fp_line
			(start 0.8636 0.4064)
			(end 1.1938 0.4064)
			(stroke
				(width 0.1)
				(type default)
			)
			(layer "B.Fab")
		)
		(fp_line
			(start 0.8636 -0.4064)
			(end 0.8636 -0.4572)
			(stroke
				(width 0.1)
				(type default)
			)
			(layer "B.Fab")
		)
		(fp_line
			(start 0.8636 -0.4572)
			(end -0.8636 -0.4572)
			(stroke
				(width 0.1)
				(type default)
			)
			(layer "B.Fab")
		)
		(fp_line
			(start -0.8636 0.4572)
			(end 0.8636 0.4572)
			(stroke
				(width 0.1)
				(type default)
			)
			(layer "B.Fab")
		)
		(fp_line
			(start -0.8636 0.4064)
			(end -0.8636 0.4572)
			(stroke
				(width 0.1)
				(type default)
			)
			(layer "B.Fab")
		)
		(fp_line
			(start -0.8636 -0.4064)
			(end -1.1938 -0.4064)
			(stroke
				(width 0.1)
				(type default)
			)
			(layer "B.Fab")
		)
		(fp_line
			(start -0.8636 -0.4572)
			(end -0.8636 -0.4064)
			(stroke
				(width 0.1)
				(type default)
			)
			(layer "B.Fab")
		)
		(fp_line
			(start -1.1938 0.4064)
			(end -0.8636 0.4064)
			(stroke
				(width 0.1)
				(type default)
			)
			(layer "B.Fab")
		)
		(fp_line
			(start -1.1938 -0.4064)
			(end -1.1938 0.4064)
			(stroke
				(width 0.1)
				(type default)
			)
			(layer "B.Fab")
		)
		(pad "1" smd rect
			(at 0.7366 0 90)
			(size 0.7112 0.8128)
			(layers "B.Cu" "B.Mask" "B.Paste")
			(net "P3V3_CLI_VPLL")
		)
		(pad "2" smd rect
			(at -0.7366 0 90)
			(size 0.7112 0.8128)
			(layers "B.Cu" "B.Mask" "B.Paste")
			(net "GND")
		)
	)
	(footprint ""
		(layer "B.Cu")
		(at 300.012354 -236.736636 90)
		(property "Reference" "R1858"
			(at 0 0 90)
			(layer "B.SilkS")
			(hide yes)
			(effects
				(font
					(size 1.27 1.27)
				)
				(justify mirror)
			)
		)
		(property "Value" ""
			(at 0 0 90)
			(layer "B.Fab")
			(effects
				(font
					(size 1.27 1.27)
				)
				(justify mirror)
			)
		)
		(duplicate_pad_numbers_are_jumpers no)
		(fp_line
			(start 0.7874 -0.4064)
			(end -0.7874 -0.4064)
			(stroke
				(width 0.1524)
				(type default)
			)
			(layer "B.SilkS")
		)
		(fp_line
			(start -0.7874 -0.4064)
			(end -0.7874 0.4064)
			(stroke
				(width 0.1524)
				(type default)
			)
			(layer "B.SilkS")
		)
		(fp_line
			(start 0.7874 0.4064)
			(end 0.7874 -0.4064)
			(stroke
				(width 0.1524)
				(type default)
			)
			(layer "B.SilkS")
		)
		(fp_line
			(start -0.7874 0.4064)
			(end 0.7874 0.4064)
			(stroke
				(width 0.1524)
				(type default)
			)
			(layer "B.SilkS")
		)
		(fp_line
			(start 0.67945 -0.305054)
			(end 0.12065 -0.305054)
			(stroke
				(width 0.1)
				(type default)
			)
			(layer "B.Fab")
		)
		(fp_line
			(start 0.12065 -0.305054)
			(end 0.12065 -0.2794)
			(stroke
				(width 0.1)
				(type default)
			)
			(layer "B.Fab")
		)
		(fp_line
			(start -0.12065 -0.3048)
			(end -0.67945 -0.3048)
			(stroke
				(width 0.1)
				(type default)
			)
			(layer "B.Fab")
		)
		(fp_line
			(start -0.67945 -0.3048)
			(end -0.67945 0.3048)
			(stroke
				(width 0.1)
				(type default)
			)
			(layer "B.Fab")
		)
		(fp_line
			(start 0.12065 -0.2794)
			(end -0.12065 -0.2794)
			(stroke
				(width 0.1)
				(type default)
			)
			(layer "B.Fab")
		)
		(fp_line
			(start -0.12065 -0.2794)
			(end -0.12065 -0.3048)
			(stroke
				(width 0.1)
				(type default)
			)
			(layer "B.Fab")
		)
		(fp_line
			(start 0.12065 0.2794)
			(end 0.12065 0.3048)
			(stroke
				(width 0.1)
				(type default)
			)
			(layer "B.Fab")
		)
		(fp_line
			(start -0.120396 0.2794)
			(end 0.12065 0.2794)
			(stroke
				(width 0.1)
				(type default)
			)
			(layer "B.Fab")
		)
		(fp_line
			(start 0.67945 0.3048)
			(end 0.67945 -0.305054)
			(stroke
				(width 0.1)
				(type default)
			)
			(layer "B.Fab")
		)
		(fp_line
			(start 0.12065 0.3048)
			(end 0.67945 0.3048)
			(stroke
				(width 0.1)
				(type default)
			)
			(layer "B.Fab")
		)
		(fp_line
			(start -0.120396 0.3048)
			(end -0.120396 0.2794)
			(stroke
				(width 0.1)
				(type default)
			)
			(layer "B.Fab")
		)
		(fp_line
			(start -0.67945 0.3048)
			(end -0.120396 0.3048)
			(stroke
				(width 0.1)
				(type default)
			)
			(layer "B.Fab")
		)
		(pad "1" smd circle
			(at 0.40005 0 270)
			(size 0 0)
			(layers "B.Cu" "B.Mask" "B.Paste")
			(net "P3V3_AUX")
		)
		(pad "2" smd circle
			(at -0.40005 0 270)
			(size 0 0)
			(layers "B.Cu" "B.Mask" "B.Paste")
			(net "RST_GPU_PERST_0_N")
		)
	)
	(footprint ""
		(layer "B.Cu")
		(at 334.01 -207.772 90)
		(property "Reference" "R4118"
			(at 0 0 90)
			(layer "B.SilkS")
			(hide yes)
			(effects
				(font
					(size 1.27 1.27)
				)
				(justify mirror)
			)
		)
		(property "Value" ""
			(at 0 0 90)
			(layer "B.Fab")
			(effects
				(font
					(size 1.27 1.27)
				)
				(justify mirror)
			)
		)
		(duplicate_pad_numbers_are_jumpers no)
		(fp_line
			(start 0.7874 -0.4064)
			(end -0.7874 -0.4064)
			(stroke
				(width 0.1524)
				(type default)
			)
			(layer "B.SilkS")
		)
		(fp_line
			(start -0.7874 -0.4064)
			(end -0.7874 0.4064)
			(stroke
				(width 0.1524)
				(type default)
			)
			(layer "B.SilkS")
		)
		(fp_line
			(start 0.7874 0.4064)
			(end 0.7874 -0.4064)
			(stroke
				(width 0.1524)
				(type default)
			)
			(layer "B.SilkS")
		)
		(fp_line
			(start -0.7874 0.4064)
			(end 0.7874 0.4064)
			(stroke
				(width 0.1524)
				(type default)
			)
			(layer "B.SilkS")
		)
		(fp_line
			(start 0.67945 -0.305054)
			(end 0.12065 -0.305054)
			(stroke
				(width 0.1)
				(type default)
			)
			(layer "B.Fab")
		)
		(fp_line
			(start 0.12065 -0.305054)
			(end 0.12065 -0.2794)
			(stroke
				(width 0.1)
				(type default)
			)
			(layer "B.Fab")
		)
		(fp_line
			(start -0.12065 -0.3048)
			(end -0.67945 -0.3048)
			(stroke
				(width 0.1)
				(type default)
			)
			(layer "B.Fab")
		)
		(fp_line
			(start -0.67945 -0.3048)
			(end -0.67945 0.3048)
			(stroke
				(width 0.1)
				(type default)
			)
			(layer "B.Fab")
		)
		(fp_line
			(start 0.12065 -0.2794)
			(end -0.12065 -0.2794)
			(stroke
				(width 0.1)
				(type default)
			)
			(layer "B.Fab")
		)
		(fp_line
			(start -0.12065 -0.2794)
			(end -0.12065 -0.3048)
			(stroke
				(width 0.1)
				(type default)
			)
			(layer "B.Fab")
		)
		(fp_line
			(start 0.12065 0.2794)
			(end 0.12065 0.3048)
			(stroke
				(width 0.1)
				(type default)
			)
			(layer "B.Fab")
		)
		(fp_line
			(start -0.120396 0.2794)
			(end 0.12065 0.2794)
			(stroke
				(width 0.1)
				(type default)
			)
			(layer "B.Fab")
		)
		(fp_line
			(start 0.67945 0.3048)
			(end 0.67945 -0.305054)
			(stroke
				(width 0.1)
				(type default)
			)
			(layer "B.Fab")
		)
		(fp_line
			(start 0.12065 0.3048)
			(end 0.67945 0.3048)
			(stroke
				(width 0.1)
				(type default)
			)
			(layer "B.Fab")
		)
		(fp_line
			(start -0.120396 0.3048)
			(end -0.120396 0.2794)
			(stroke
				(width 0.1)
				(type default)
			)
			(layer "B.Fab")
		)
		(fp_line
			(start -0.67945 0.3048)
			(end -0.120396 0.3048)
			(stroke
				(width 0.1)
				(type default)
			)
			(layer "B.Fab")
		)
		(pad "1" smd circle
			(at 0.40005 0 270)
			(size 0 0)
			(layers "B.Cu" "B.Mask" "B.Paste")
			(net "SSD8_CLK_EN_N")
		)
		(pad "2" smd circle
			(at -0.40005 0 270)
			(size 0 0)
			(layers "B.Cu" "B.Mask" "B.Paste")
			(net "SSD8_CLK_EN_R_N")
		)
	)
	(footprint ""
		(layer "B.Cu")
		(at 3.079242 -270.585946)
		(property "Reference" "C4220"
			(at 0 0 0)
			(layer "B.SilkS")
			(hide yes)
			(effects
				(font
					(size 1.27 1.27)
				)
				(justify mirror)
			)
		)
		(property "Value" ""
			(at 0 0 0)
			(layer "B.Fab")
			(effects
				(font
					(size 1.27 1.27)
				)
				(justify mirror)
			)
		)
		(duplicate_pad_numbers_are_jumpers no)
		(fp_line
			(start -1.2954 -0.5842)
			(end -1.2954 0.5842)
			(stroke
				(width 0.1524)
				(type default)
			)
			(layer "B.SilkS")
		)
		(fp_line
			(start -1.2954 0.5842)
			(end 1.2954 0.5842)
			(stroke
				(width 0.1524)
				(type default)
			)
			(layer "B.SilkS")
		)
		(fp_line
			(start 1.2954 -0.5842)
			(end -1.2954 -0.5842)
			(stroke
				(width 0.1524)
				(type default)
			)
			(layer "B.SilkS")
		)
		(fp_line
			(start 1.2954 0.5842)
			(end 1.2954 -0.5842)
			(stroke
				(width 0.1524)
				(type default)
			)
			(layer "B.SilkS")
		)
		(fp_line
			(start -1.1938 -0.4064)
			(end -1.1938 0.4064)
			(stroke
				(width 0.1)
				(type default)
			)
			(layer "B.Fab")
		)
		(fp_line
			(start -1.1938 0.4064)
			(end -0.8636 0.4064)
			(stroke
				(width 0.1)
				(type default)
			)
			(layer "B.Fab")
		)
		(fp_line
			(start -0.8636 -0.4572)
			(end -0.8636 -0.4064)
			(stroke
				(width 0.1)
				(type default)
			)
			(layer "B.Fab")
		)
		(fp_line
			(start -0.8636 -0.4064)
			(end -1.1938 -0.4064)
			(stroke
				(width 0.1)
				(type default)
			)
			(layer "B.Fab")
		)
		(fp_line
			(start -0.8636 0.4064)
			(end -0.8636 0.4572)
			(stroke
				(width 0.1)
				(type default)
			)
			(layer "B.Fab")
		)
		(fp_line
			(start -0.8636 0.4572)
			(end 0.8636 0.4572)
			(stroke
				(width 0.1)
				(type default)
			)
			(layer "B.Fab")
		)
		(fp_line
			(start 0.8636 -0.4572)
			(end -0.8636 -0.4572)
			(stroke
				(width 0.1)
				(type default)
			)
			(layer "B.Fab")
		)
		(fp_line
			(start 0.8636 -0.4064)
			(end 0.8636 -0.4572)
			(stroke
				(width 0.1)
				(type default)
			)
			(layer "B.Fab")
		)
		(fp_line
			(start 0.8636 0.4064)
			(end 1.1938 0.4064)
			(stroke
				(width 0.1)
				(type default)
			)
			(layer "B.Fab")
		)
		(fp_line
			(start 0.8636 0.4572)
			(end 0.8636 0.4064)
			(stroke
				(width 0.1)
				(type default)
			)
			(layer "B.Fab")
		)
		(fp_line
			(start 1.1938 -0.4064)
			(end 0.8636 -0.4064)
			(stroke
				(width 0.1)
				(type default)
			)
			(layer "B.Fab")
		)
		(fp_line
			(start 1.1938 0.4064)
			(end 1.1938 -0.4064)
			(stroke
				(width 0.1)
				(type default)
			)
			(layer "B.Fab")
		)
		(pad "1" smd rect
			(at 0.7366 0 270)
			(size 0.7112 0.8128)
			(layers "B.Cu" "B.Mask" "B.Paste")
			(net "P1V25_PEX0")
		)
		(pad "2" smd rect
			(at -0.7366 0 270)
			(size 0.7112 0.8128)
			(layers "B.Cu" "B.Mask" "B.Paste")
			(net "GND")
		)
	)
	(footprint ""
		(layer "B.Cu")
		(at 363.332776 -152.71115 90)
		(property "Reference" "R764"
			(at 0 0 90)
			(layer "B.SilkS")
			(hide yes)
			(effects
				(font
					(size 1.27 1.27)
				)
				(justify mirror)
			)
		)
		(property "Value" ""
			(at 0 0 90)
			(layer "B.Fab")
			(effects
				(font
					(size 1.27 1.27)
				)
				(justify mirror)
			)
		)
		(duplicate_pad_numbers_are_jumpers no)
		(fp_line
			(start 0.7874 -0.4064)
			(end -0.7874 -0.4064)
			(stroke
				(width 0.1524)
				(type default)
			)
			(layer "B.SilkS")
		)
		(fp_line
			(start -0.7874 -0.4064)
			(end -0.7874 0.4064)
			(stroke
				(width 0.1524)
				(type default)
			)
			(layer "B.SilkS")
		)
		(fp_line
			(start 0.7874 0.4064)
			(end 0.7874 -0.4064)
			(stroke
				(width 0.1524)
				(type default)
			)
			(layer "B.SilkS")
		)
		(fp_line
			(start -0.7874 0.4064)
			(end 0.7874 0.4064)
			(stroke
				(width 0.1524)
				(type default)
			)
			(layer "B.SilkS")
		)
		(fp_line
			(start 0.67945 -0.305054)
			(end 0.12065 -0.305054)
			(stroke
				(width 0.1)
				(type default)
			)
			(layer "B.Fab")
		)
		(fp_line
			(start 0.12065 -0.305054)
			(end 0.12065 -0.2794)
			(stroke
				(width 0.1)
				(type default)
			)
			(layer "B.Fab")
		)
		(fp_line
			(start -0.12065 -0.3048)
			(end -0.67945 -0.3048)
			(stroke
				(width 0.1)
				(type default)
			)
			(layer "B.Fab")
		)
		(fp_line
			(start -0.67945 -0.3048)
			(end -0.67945 0.3048)
			(stroke
				(width 0.1)
				(type default)
			)
			(layer "B.Fab")
		)
		(fp_line
			(start 0.12065 -0.2794)
			(end -0.12065 -0.2794)
			(stroke
				(width 0.1)
				(type default)
			)
			(layer "B.Fab")
		)
		(fp_line
			(start -0.12065 -0.2794)
			(end -0.12065 -0.3048)
			(stroke
				(width 0.1)
				(type default)
			)
			(layer "B.Fab")
		)
		(fp_line
			(start 0.12065 0.2794)
			(end 0.12065 0.3048)
			(stroke
				(width 0.1)
				(type default)
			)
			(layer "B.Fab")
		)
		(fp_line
			(start -0.120396 0.2794)
			(end 0.12065 0.2794)
			(stroke
				(width 0.1)
				(type default)
			)
			(layer "B.Fab")
		)
		(fp_line
			(start 0.67945 0.3048)
			(end 0.67945 -0.305054)
			(stroke
				(width 0.1)
				(type default)
			)
			(layer "B.Fab")
		)
		(fp_line
			(start 0.12065 0.3048)
			(end 0.67945 0.3048)
			(stroke
				(width 0.1)
				(type default)
			)
			(layer "B.Fab")
		)
		(fp_line
			(start -0.120396 0.3048)
			(end -0.120396 0.2794)
			(stroke
				(width 0.1)
				(type default)
			)
			(layer "B.Fab")
		)
		(fp_line
			(start -0.67945 0.3048)
			(end -0.120396 0.3048)
			(stroke
				(width 0.1)
				(type default)
			)
			(layer "B.Fab")
		)
		(pad "1" smd circle
			(at 0.40005 0 270)
			(size 0 0)
			(layers "B.Cu" "B.Mask" "B.Paste")
			(net "SMB_BIC_I2C6_MUX_NIC_ADC_R_SCL")
		)
		(pad "2" smd circle
			(at -0.40005 0 270)
			(size 0 0)
			(layers "B.Cu" "B.Mask" "B.Paste")
			(net "SMB_NIC7_ADC_SCL")
		)
	)
	(footprint ""
		(layer "B.Cu")
		(at 99.35337 -334.083406 180)
		(property "Reference" "R1230"
			(at 0 0 0)
			(layer "B.SilkS")
			(hide yes)
			(effects
				(font
					(size 1.27 1.27)
				)
				(justify mirror)
			)
		)
		(property "Value" ""
			(at 0 0 0)
			(layer "B.Fab")
			(effects
				(font
					(size 1.27 1.27)
				)
				(justify mirror)
			)
		)
		(duplicate_pad_numbers_are_jumpers no)
		(fp_line
			(start 0.7874 0.4064)
			(end 0.7874 -0.4064)
			(stroke
				(width 0.1524)
				(type default)
			)
			(layer "B.SilkS")
		)
		(fp_line
			(start 0.7874 -0.4064)
			(end -0.7874 -0.4064)
			(stroke
				(width 0.1524)
				(type default)
			)
			(layer "B.SilkS")
		)
		(fp_line
			(start -0.7874 0.4064)
			(end 0.7874 0.4064)
			(stroke
				(width 0.1524)
				(type default)
			)
			(layer "B.SilkS")
		)
		(fp_line
			(start -0.7874 -0.4064)
			(end -0.7874 0.4064)
			(stroke
				(width 0.1524)
				(type default)
			)
			(layer "B.SilkS")
		)
		(fp_line
			(start 0.67945 0.3048)
			(end 0.67945 -0.305054)
			(stroke
				(width 0.1)
				(type default)
			)
			(layer "B.Fab")
		)
		(fp_line
			(start 0.67945 -0.305054)
			(end 0.12065 -0.305054)
			(stroke
				(width 0.1)
				(type default)
			)
			(layer "B.Fab")
		)
		(fp_line
			(start 0.12065 0.3048)
			(end 0.67945 0.3048)
			(stroke
				(width 0.1)
				(type default)
			)
			(layer "B.Fab")
		)
		(fp_line
			(start 0.12065 0.2794)
			(end 0.12065 0.3048)
			(stroke
				(width 0.1)
				(type default)
			)
			(layer "B.Fab")
		)
		(fp_line
			(start 0.12065 -0.2794)
			(end -0.12065 -0.2794)
			(stroke
				(width 0.1)
				(type default)
			)
			(layer "B.Fab")
		)
		(fp_line
			(start 0.12065 -0.305054)
			(end 0.12065 -0.2794)
			(stroke
				(width 0.1)
				(type default)
			)
			(layer "B.Fab")
		)
		(fp_line
			(start -0.120396 0.3048)
			(end -0.120396 0.2794)
			(stroke
				(width 0.1)
				(type default)
			)
			(layer "B.Fab")
		)
		(fp_line
			(start -0.120396 0.2794)
			(end 0.12065 0.2794)
			(stroke
				(width 0.1)
				(type default)
			)
			(layer "B.Fab")
		)
		(fp_line
			(start -0.12065 -0.2794)
			(end -0.12065 -0.3048)
			(stroke
				(width 0.1)
				(type default)
			)
			(layer "B.Fab")
		)
		(fp_line
			(start -0.12065 -0.3048)
			(end -0.67945 -0.3048)
			(stroke
				(width 0.1)
				(type default)
			)
			(layer "B.Fab")
		)
		(fp_line
			(start -0.67945 0.3048)
			(end -0.120396 0.3048)
			(stroke
				(width 0.1)
				(type default)
			)
			(layer "B.Fab")
		)
		(fp_line
			(start -0.67945 -0.3048)
			(end -0.67945 0.3048)
			(stroke
				(width 0.1)
				(type default)
			)
			(layer "B.Fab")
		)
		(pad "1" smd circle
			(at 0.40005 0)
			(size 0 0)
			(layers "B.Cu" "B.Mask" "B.Paste")
			(net "CLK_100M_DB800ZL_PEX2_S0_R_DN")
		)
		(pad "2" smd circle
			(at -0.40005 0)
			(size 0 0)
			(layers "B.Cu" "B.Mask" "B.Paste")
			(net "CLK_100M_DB800ZL_PEX2_S0_DN")
		)
	)
)
